(kicad_pcb
	(version 20241229)
	(generator "pcbnew")
	(generator_version "9.0")
	(general
		(thickness 1.599998)
		(legacy_teardrops no)
	)
	(paper "A4")
	(title_block
		(date "2023-02-12")
		(rev "1.1.5")
		(comment 9 "footprints 50-55 of 473")
	)
	(layers
		(0 "F.Cu" signal)
		(4 "In1.Cu" power "In1.GND")
		(6 "In2.Cu" signal)
		(8 "In3.Cu" power "In3.GND")
		(10 "In4.Cu" power "In4.VCC")
		(12 "In5.Cu" signal)
		(14 "In6.Cu" power "In6.VCC")
		(2 "B.Cu" signal)
		(9 "F.Adhes" user "F.Adhesive")
		(11 "B.Adhes" user "B.Adhesive")
		(13 "F.Paste" user)
		(15 "B.Paste" user)
		(5 "F.SilkS" user "F.Silkscreen")
		(7 "B.SilkS" user "B.Silkscreen")
		(1 "F.Mask" user)
		(3 "B.Mask" user)
		(17 "Dwgs.User" user "User.Drawings")
		(19 "Cmts.User" user "User.Comments")
		(21 "Eco1.User" user "User.Eco1")
		(23 "Eco2.User" user "User.Eco2")
		(25 "Edge.Cuts" user)
		(27 "Margin" user)
		(31 "F.CrtYd" user "F.Courtyard")
		(29 "B.CrtYd" user "B.Courtyard")
		(35 "F.Fab" user)
		(33 "B.Fab" user)
	)
	(footprint "antmicro-footprints:R_0402_1005Metric"
		(layer "F.Cu")
		(at 173.756 130.082 -90)
		(descr "Resistor SMD 0402")
		(tags "resistor SMD 0402")
		(property "Reference" "R35"
			(at -0.782 -0.403 270)
			(layer "F.SilkS")
			(effects
				(font
					(size 0.7 0.7)
					(thickness 0.15)
				)
				(justify left bottom)
			)
		)
		(property "Value" "R_20k_0402"
			(at 0 1.4 270)
			(layer "F.Fab")
			(effects
				(font
					(size 0.7 0.7)
					(thickness 0.15)
				)
				(justify left bottom)
			)
		)
		(property "Description" "20k resistor in 0402 package with 1% tolerance"
			(at 0 0 270)
			(layer "F.Fab")
			(hide yes)
			(effects
				(font
					(size 1.27 1.27)
					(thickness 0.15)
				)
			)
		)
		(property "Author" "Antmicro"
			(at 43.674 303.838 0)
			(layer "F.Fab")
			(hide yes)
			(effects
				(font
					(size 1 1)
					(thickness 0.15)
				)
			)
		)
		(property "License" "Apache-2.0"
			(at 43.674 303.838 0)
			(layer "F.Fab")
			(hide yes)
			(effects
				(font
					(size 1 1)
					(thickness 0.15)
				)
			)
		)
		(property "MPN" "CR0402-FX-2002GLF"
			(at 43.674 303.838 0)
			(layer "F.Fab")
			(hide yes)
			(effects
				(font
					(size 1 1)
					(thickness 0.15)
				)
			)
		)
		(property "Manufacturer" "Bourns"
			(at 43.674 303.838 0)
			(layer "F.Fab")
			(hide yes)
			(effects
				(font
					(size 1 1)
					(thickness 0.15)
				)
			)
		)
		(property "Tolerance" "1%"
			(at 43.674 303.838 0)
			(layer "F.Fab")
			(hide yes)
			(effects
				(font
					(size 1 1)
					(thickness 0.15)
				)
			)
		)
		(property "Val" "20k"
			(at 43.674 303.838 0)
			(layer "F.Fab")
			(hide yes)
			(effects
				(font
					(size 1 1)
					(thickness 0.15)
				)
			)
		)
		(sheetname "Interfaces")
		(sheetfile "interfaces.kicad_sch")
		(attr smd)
		(fp_rect
			(start -0.93 -0.47)
			(end 0.93 0.47)
			(stroke
				(width 0.05)
				(type solid)
			)
			(fill no)
			(layer "F.CrtYd")
		)
		(fp_rect
			(start -0.5 -0.25)
			(end 0.5 0.25)
			(stroke
				(width 0.15)
				(type solid)
			)
			(fill no)
			(layer "F.Fab")
		)
		(pad "1" smd roundrect
			(at -0.485 0 270)
			(size 0.59 0.64)
			(layers "F.Cu" "F.Mask" "F.Paste")
			(roundrect_rratio 0.25)
			(net 459 "3V3_SYS")
			(pintype "passive")
		)
		(pad "2" smd roundrect
			(at 0.485 0 270)
			(size 0.59 0.64)
			(layers "F.Cu" "F.Mask" "F.Paste")
			(roundrect_rratio 0.25)
			(net 195 "SD_CMD")
			(pintype "passive")
		)
	)
	(footprint "antmicro-footprints:R_0402_1005Metric"
		(layer "F.Cu")
		(at 179.344 130.082 -90)
		(descr "Resistor SMD 0402")
		(tags "resistor SMD 0402")
		(property "Reference" "R32"
			(at -0.782 -0.431 270)
			(layer "F.SilkS")
			(effects
				(font
					(size 0.7 0.7)
					(thickness 0.15)
				)
				(justify left bottom)
			)
		)
		(property "Value" "R_20k_0402"
			(at 0 1.4 270)
			(layer "F.Fab")
			(effects
				(font
					(size 0.7 0.7)
					(thickness 0.15)
				)
				(justify left bottom)
			)
		)
		(property "Description" "20k resistor in 0402 package with 1% tolerance"
			(at 0 0 270)
			(layer "F.Fab")
			(hide yes)
			(effects
				(font
					(size 1.27 1.27)
					(thickness 0.15)
				)
			)
		)
		(property "Author" "Antmicro"
			(at 49.262 309.426 0)
			(layer "F.Fab")
			(hide yes)
			(effects
				(font
					(size 1 1)
					(thickness 0.15)
				)
			)
		)
		(property "License" "Apache-2.0"
			(at 49.262 309.426 0)
			(layer "F.Fab")
			(hide yes)
			(effects
				(font
					(size 1 1)
					(thickness 0.15)
				)
			)
		)
		(property "MPN" "CR0402-FX-2002GLF"
			(at 49.262 309.426 0)
			(layer "F.Fab")
			(hide yes)
			(effects
				(font
					(size 1 1)
					(thickness 0.15)
				)
			)
		)
		(property "Manufacturer" "Bourns"
			(at 49.262 309.426 0)
			(layer "F.Fab")
			(hide yes)
			(effects
				(font
					(size 1 1)
					(thickness 0.15)
				)
			)
		)
		(property "Tolerance" "1%"
			(at 49.262 309.426 0)
			(layer "F.Fab")
			(hide yes)
			(effects
				(font
					(size 1 1)
					(thickness 0.15)
				)
			)
		)
		(property "Val" "20k"
			(at 49.262 309.426 0)
			(layer "F.Fab")
			(hide yes)
			(effects
				(font
					(size 1 1)
					(thickness 0.15)
				)
			)
		)
		(sheetname "Interfaces")
		(sheetfile "interfaces.kicad_sch")
		(attr smd)
		(fp_rect
			(start -0.93 -0.47)
			(end 0.93 0.47)
			(stroke
				(width 0.05)
				(type solid)
			)
			(fill no)
			(layer "F.CrtYd")
		)
		(fp_rect
			(start -0.5 -0.25)
			(end 0.5 0.25)
			(stroke
				(width 0.15)
				(type solid)
			)
			(fill no)
			(layer "F.Fab")
		)
		(pad "1" smd roundrect
			(at -0.485 0 270)
			(size 0.59 0.64)
			(layers "F.Cu" "F.Mask" "F.Paste")
			(roundrect_rratio 0.25)
			(net 459 "3V3_SYS")
			(pintype "passive")
		)
		(pad "2" smd roundrect
			(at 0.485 0 270)
			(size 0.59 0.64)
			(layers "F.Cu" "F.Mask" "F.Paste")
			(roundrect_rratio 0.25)
			(net 192 "SD_DAT1")
			(pintype "passive")
		)
	)
	(footprint "antmicro-footprints:FB_0603_1608Metric"
		(layer "F.Cu")
		(at 142.469328 116.527157 180)
		(property "Reference" "FB1"
			(at 0.969328 -1.472843 180)
			(layer "F.SilkS")
			(effects
				(font
					(size 0.7 0.7)
					(thickness 0.15)
				)
				(justify left bottom)
			)
		)
		(property "Value" "FB_600Z_0.5A_0603"
			(at 0 1.5 180)
			(layer "F.Fab")
			(effects
				(font
					(size 0.7 0.7)
					(thickness 0.15)
				)
				(justify left bottom)
			)
		)
		(property "Description" "Ferrite Beads WE-TMSB Suppression 240Ohm 200mA "
			(at 0 0 180)
			(layer "F.Fab")
			(hide yes)
			(effects
				(font
					(size 1.27 1.27)
					(thickness 0.15)
				)
			)
		)
		(property "Author" "Antmicro"
			(at 284.938656 233.054314 0)
			(layer "F.Fab")
			(hide yes)
			(effects
				(font
					(size 1 1)
					(thickness 0.15)
				)
			)
		)
		(property "License" "Apache-2.0"
			(at 284.938656 233.054314 0)
			(layer "F.Fab")
			(hide yes)
			(effects
				(font
					(size 1 1)
					(thickness 0.15)
				)
			)
		)
		(property "MPN" "BLM18AG601SN1D"
			(at 284.938656 233.054314 0)
			(layer "F.Fab")
			(hide yes)
			(effects
				(font
					(size 1 1)
					(thickness 0.15)
				)
			)
		)
		(property "Manufacturer" "Murata"
			(at 284.938656 233.054314 0)
			(layer "F.Fab")
			(hide yes)
			(effects
				(font
					(size 1 1)
					(thickness 0.15)
				)
			)
		)
		(sheetname "Interfaces")
		(sheetfile "interfaces.kicad_sch")
		(attr smd)
		(fp_line
			(start -0.196 0.406)
			(end 0.193 0.406)
			(stroke
				(width 0.15)
				(type solid)
			)
			(layer "F.SilkS")
		)
		(fp_line
			(start -0.196 -0.408)
			(end 0.193 -0.408)
			(stroke
				(width 0.15)
				(type solid)
			)
			(layer "F.SilkS")
		)
		(fp_rect
			(start -1.3 -0.6)
			(end 1.3 0.6)
			(stroke
				(width 0.05)
				(type solid)
			)
			(fill no)
			(layer "F.CrtYd")
		)
		(fp_line
			(start 0.8 0.406)
			(end -0.803 0.406)
			(stroke
				(width 0.15)
				(type solid)
			)
			(layer "F.Fab")
		)
		(fp_line
			(start 0.8 -0.408)
			(end 0.8 0.406)
			(stroke
				(width 0.15)
				(type solid)
			)
			(layer "F.Fab")
		)
		(fp_line
			(start 0.8 -0.408)
			(end -0.803 -0.408)
			(stroke
				(width 0.15)
				(type solid)
			)
			(layer "F.Fab")
		)
		(fp_line
			(start -0.803 0.406)
			(end -0.803 -0.408)
			(stroke
				(width 0.15)
				(type solid)
			)
			(layer "F.Fab")
		)
		(pad "1" smd roundrect
			(at -0.891 0 180)
			(size 0.762 1.09)
			(layers "F.Cu" "F.Mask" "F.Paste")
			(roundrect_rratio 0.15)
			(net 459 "3V3_SYS")
			(pintype "passive")
		)
		(pad "2" smd roundrect
			(at 0.888 0 180)
			(size 0.762 1.09)
			(layers "F.Cu" "F.Mask" "F.Paste")
			(roundrect_rratio 0.15)
			(net 652 "/Interfaces/VPLL")
			(pintype "passive")
		)
	)
	(footprint "antmicro-footprints:C_0402_1005Metric"
		(layer "F.Cu")
		(at 137.536328 117.371157 -90)
		(descr "Capacitor SMD 0402")
		(tags "capacitor SMD 0402")
		(property "Reference" "C20"
			(at 2.928843 -0.363672 270)
			(layer "F.SilkS")
			(effects
				(font
					(size 0.7 0.7)
					(thickness 0.15)
				)
				(justify left bottom)
			)
		)
		(property "Value" "C_18p_0402"
			(at 0 1.4 270)
			(layer "F.Fab")
			(effects
				(font
					(size 0.7 0.7)
					(thickness 0.15)
				)
				(justify left bottom)
			)
		)
		(property "Description" " "
			(at 0 0 270)
			(layer "F.Fab")
			(hide yes)
			(effects
				(font
					(size 1.27 1.27)
					(thickness 0.15)
				)
			)
		)
		(property "Author" "Antmicro"
			(at 20.165171 254.907485 0)
			(layer "F.Fab")
			(hide yes)
			(effects
				(font
					(size 1 1)
					(thickness 0.15)
				)
			)
		)
		(property "Dielectric" ""
			(at 20.165171 254.907485 0)
			(layer "F.Fab")
			(hide yes)
			(effects
				(font
					(size 1 1)
					(thickness 0.15)
				)
			)
		)
		(property "License" "Apache-2.0"
			(at 20.165171 254.907485 0)
			(layer "F.Fab")
			(hide yes)
			(effects
				(font
					(size 1 1)
					(thickness 0.15)
				)
			)
		)
		(property "MPN" "MC0402N180J500CT"
			(at 20.165171 254.907485 0)
			(layer "F.Fab")
			(hide yes)
			(effects
				(font
					(size 1 1)
					(thickness 0.15)
				)
			)
		)
		(property "Manufacturer" "Multicomp"
			(at 20.165171 254.907485 0)
			(layer "F.Fab")
			(hide yes)
			(effects
				(font
					(size 1 1)
					(thickness 0.15)
				)
			)
		)
		(property "Val" "18p"
			(at 20.165171 254.907485 0)
			(layer "F.Fab")
			(hide yes)
			(effects
				(font
					(size 1 1)
					(thickness 0.15)
				)
			)
		)
		(property "Voltage" ""
			(at 20.165171 254.907485 0)
			(layer "F.Fab")
			(hide yes)
			(effects
				(font
					(size 1 1)
					(thickness 0.15)
				)
			)
		)
		(sheetname "Interfaces")
		(sheetfile "interfaces.kicad_sch")
		(attr smd)
		(fp_rect
			(start -0.94 -0.47)
			(end 0.94 0.47)
			(stroke
				(width 0.05)
				(type solid)
			)
			(fill no)
			(layer "F.CrtYd")
		)
		(fp_rect
			(start -0.499 -0.249)
			(end 0.499 0.249)
			(stroke
				(width 0.15)
				(type solid)
			)
			(fill no)
			(layer "F.Fab")
		)
		(pad "1" smd roundrect
			(at -0.484 0 270)
			(size 0.59 0.64)
			(layers "F.Cu" "F.Mask" "F.Paste")
			(roundrect_rratio 0.25)
			(net 5 "GND")
			(pintype "passive")
		)
		(pad "2" smd roundrect
			(at 0.484 0 270)
			(size 0.59 0.64)
			(layers "F.Cu" "F.Mask" "F.Paste")
			(roundrect_rratio 0.25)
			(net 4 "Net-(U4-OSCO)")
			(pintype "passive")
		)
	)
	(footprint "antmicro-footprints:R_0402_1005Metric"
		(layer "F.Cu")
		(at 116.9142 118.975 180)
		(descr "Resistor SMD 0402")
		(tags "resistor SMD 0402")
		(property "Reference" "R104"
			(at 3.6142 -0.525 180)
			(layer "F.SilkS")
			(effects
				(font
					(size 0.7 0.7)
					(thickness 0.15)
				)
				(justify left bottom)
			)
		)
		(property "Value" "R_53k6_0402"
			(at 0 1.4 180)
			(layer "F.Fab")
			(effects
				(font
					(size 0.7 0.7)
					(thickness 0.15)
				)
				(justify left bottom)
			)
		)
		(property "Description" "53k6 resistor in 0402 package with 1% tolerance"
			(at 0 0 180)
			(layer "F.Fab")
			(hide yes)
			(effects
				(font
					(size 1.27 1.27)
					(thickness 0.15)
				)
			)
		)
		(property "Author" "Antmicro"
			(at 233.8284 237.95 0)
			(layer "F.Fab")
			(hide yes)
			(effects
				(font
					(size 1 1)
					(thickness 0.15)
				)
			)
		)
		(property "License" "Apache-2.0"
			(at 233.8284 237.95 0)
			(layer "F.Fab")
			(hide yes)
			(effects
				(font
					(size 1 1)
					(thickness 0.15)
				)
			)
		)
		(property "MPN" "CR0402-FX-5362GLF"
			(at 233.8284 237.95 0)
			(layer "F.Fab")
			(hide yes)
			(effects
				(font
					(size 1 1)
					(thickness 0.15)
				)
			)
		)
		(property "Manufacturer" "Bourns"
			(at 233.8284 237.95 0)
			(layer "F.Fab")
			(hide yes)
			(effects
				(font
					(size 1 1)
					(thickness 0.15)
				)
			)
		)
		(property "Tolerance" "1%"
			(at 233.8284 237.95 0)
			(layer "F.Fab")
			(hide yes)
			(effects
				(font
					(size 1 1)
					(thickness 0.15)
				)
			)
		)
		(property "Val" "53k6"
			(at 233.8284 237.95 0)
			(layer "F.Fab")
			(hide yes)
			(effects
				(font
					(size 1 1)
					(thickness 0.15)
				)
			)
		)
		(sheetname "Supply")
		(sheetfile "supply.kicad_sch")
		(attr smd)
		(fp_rect
			(start -0.93 -0.47)
			(end 0.93 0.47)
			(stroke
				(width 0.05)
				(type solid)
			)
			(fill no)
			(layer "F.CrtYd")
		)
		(fp_rect
			(start -0.5 -0.25)
			(end 0.5 0.25)
			(stroke
				(width 0.15)
				(type solid)
			)
			(fill no)
			(layer "F.Fab")
		)
		(pad "1" smd roundrect
			(at -0.485 0 180)
			(size 0.59 0.64)
			(layers "F.Cu" "F.Mask" "F.Paste")
			(roundrect_rratio 0.25)
			(net 244 "Net-(R103-Pad2)")
			(pintype "passive")
		)
		(pad "2" smd roundrect
			(at 0.485 0 180)
			(size 0.59 0.64)
			(layers "F.Cu" "F.Mask" "F.Paste")
			(roundrect_rratio 0.25)
			(net 660 "/Supply/5V0_FB")
			(pintype "passive")
		)
	)
	(footprint "antmicro-footprints:LED_0603_1608Metric_G"
		(layer "F.Cu")
		(at 205.286328 86.620008 180)
		(descr "LED SMD 0603 Green")
		(tags "LED SMD 0603 Green")
		(property "Reference" "D9"
			(at 0.786328 -1.379992 180)
			(layer "F.SilkS")
			(effects
				(font
					(size 0.7 0.7)
					(thickness 0.15)
				)
				(justify left bottom)
			)
		)
		(property "Value" "LED_G_0603_KP-1608CGCK"
			(at 0 1.6 180)
			(layer "F.Fab")
			(effects
				(font
					(size 0.7 0.7)
					(thickness 0.15)
				)
				(justify left bottom)
			)
		)
		(property "Author" "Antmicro"
			(at 410.572656 173.240016 0)
			(layer "F.Fab")
			(hide yes)
			(effects
				(font
					(size 1 1)
					(thickness 0.15)
				)
			)
		)
		(property "License" "Apache-2.0"
			(at 410.572656 173.240016 0)
			(layer "F.Fab")
			(hide yes)
			(effects
				(font
					(size 1 1)
					(thickness 0.15)
				)
			)
		)
		(property "MPN" "KP-1608CGCK"
			(at 410.572656 173.240016 0)
			(layer "F.Fab")
			(hide yes)
			(effects
				(font
					(size 1 1)
					(thickness 0.15)
				)
			)
		)
		(property "Manufacturer" "Kingbright"
			(at 410.572656 173.240016 0)
			(layer "F.Fab")
			(hide yes)
			(effects
				(font
					(size 1 1)
					(thickness 0.15)
				)
			)
		)
		(sheetname "Config SPI flash")
		(sheetfile "config-spi.kicad_sch")
		(attr smd)
		(fp_line
			(start 1.25 0.32)
			(end 1.25 -0.32)
			(stroke
				(width 0.15)
				(type solid)
			)
			(layer "F.SilkS")
		)
		(fp_line
			(start 0.093672 -8e-06)
			(end 0.293672 -8e-06)
			(stroke
				(width 0.1)
				(type solid)
			)
			(layer "F.SilkS")
		)
		(fp_line
			(start 0.093672 -8e-06)
			(end -0.106328 0.199992)
			(stroke
				(width 0.1)
				(type solid)
			)
			(layer "F.SilkS")
		)
		(fp_line
			(start 0.093672 -0.200008)
			(end 0.093672 0.199992)
			(stroke
				(width 0.1)
				(type solid)
			)
			(layer "F.SilkS")
		)
		(fp_line
			(start -0.106328 -8e-06)
			(end -0.29 0)
			(stroke
				(width 0.1)
				(type solid)
			)
			(layer "F.SilkS")
		)
		(fp_line
			(start -0.106328 -0.200008)
			(end 0.093672 -8e-06)
			(stroke
				(width 0.1)
				(type solid)
			)
			(layer "F.SilkS")
		)
		(fp_line
			(start -0.106328 -0.200008)
			(end -0.106328 0.199992)
			(stroke
				(width 0.1)
				(type solid)
			)
			(layer "F.SilkS")
		)
		(fp_line
			(start -0.27 0.351)
			(end 0.27 0.351)
			(stroke
				(width 0.15)
				(type solid)
			)
			(layer "F.SilkS")
		)
		(fp_line
			(start -0.27 -0.35)
			(end 0.27 -0.35)
			(stroke
				(width 0.15)
				(type solid)
			)
			(layer "F.SilkS")
		)
		(fp_rect
			(start 1.26 0.65)
			(end -1.26 -0.65)
			(stroke
				(width 0.05)
				(type solid)
			)
			(fill no)
			(layer "F.CrtYd")
		)
		(fp_line
			(start 0.199 0.202)
			(end 0.199 -0.1)
			(stroke
				(width 0.15)
				(type solid)
			)
			(layer "F.Fab")
		)
		(fp_line
			(start 0.199 0)
			(end 0.597 0)
			(stroke
				(width 0.15)
				(type solid)
			)
			(layer "F.Fab")
		)
		(fp_line
			(start 0.199 -0.2)
			(end 0.199 -0.1)
			(stroke
				(width 0.15)
				(type solid)
			)
			(layer "F.Fab")
		)
		(fp_line
			(start 0.101 0)
			(end -0.201 -0.2)
			(stroke
				(width 0.15)
				(type solid)
			)
			(layer "F.Fab")
		)
		(fp_line
			(start -0.201 0.202)
			(end 0.101 0)
			(stroke
				(width 0.15)
				(type solid)
			)
			(layer "F.Fab")
		)
		(fp_line
			(start -0.201 0)
			(end -0.201 0.202)
			(stroke
				(width 0.15)
				(type solid)
			)
			(layer "F.Fab")
		)
		(fp_line
			(start -0.201 -0.2)
			(end -0.201 0)
			(stroke
				(width 0.15)
				(type solid)
			)
			(layer "F.Fab")
		)
		(fp_line
			(start -0.599 0)
			(end -0.201 0)
			(stroke
				(width 0.15)
				(type solid)
			)
			(layer "F.Fab")
		)
		(fp_rect
			(start -0.848 -0.4)
			(end 0.85 0.402)
			(stroke
				(width 0.15)
				(type solid)
			)
			(fill no)
			(layer "F.Fab")
		)
		(pad "1" smd rect
			(at -0.75 0)
			(size 0.8 0.8)
			(layers "F.Cu" "F.Mask" "F.Paste")
			(net 459 "3V3_SYS")
			(pinfunction "1")
			(pintype "passive")
		)
		(pad "2" smd rect
			(at 0.75 0)
			(size 0.8 0.8)
			(layers "F.Cu" "F.Mask" "F.Paste")
			(net 67 "Net-(D9-Pad2)")
			(pinfunction "2")
			(pintype "passive")
		)
	)
)
